(kicad_pcb
	(version 20260206)
	(generator "pcbnew")
	(generator_version "10.0")
	(general
		(thickness 1.6)
		(legacy_teardrops no)
	)
	(paper "A4")
	(title_block
		(title "12092022_DA0F0TMDCD0_F0T_Management_Board_D_brd_V3_OCP.brd")
		(comment 1 "Grand Teton / footprints 1367-1373 of 1440")
	)
	(layers
		(0 "F.Cu" signal "TOP")
		(4 "In1.Cu" signal "GND")
		(6 "In2.Cu" signal "IN1")
		(8 "In3.Cu" signal "GND1")
		(10 "In4.Cu" signal "IN2")
		(12 "In5.Cu" signal "VCC")
		(14 "In6.Cu" signal "VCC1")
		(16 "In7.Cu" signal "IN3")
		(18 "In8.Cu" signal "GND2")
		(20 "In9.Cu" signal "IN4")
		(22 "In10.Cu" signal "GND3")
		(2 "B.Cu" signal "BOTTOM")
		(9 "F.Adhes" user "F.Adhesive")
		(11 "B.Adhes" user "B.Adhesive")
		(13 "F.Paste" user "Package Geometry/Pastemask Top")
		(15 "B.Paste" user "Package Geometry/Pastemask Bottom")
		(5 "F.SilkS" user "Ref Des/Silkscreen Top")
		(7 "B.SilkS" user "Ref Des/Silkscreen Bottom")
		(1 "F.Mask" user "Board Geometry/Soldermask Top")
		(3 "B.Mask" user "Board Geometry/Soldermask Bottom")
		(17 "Dwgs.User" user "User.Drawings")
		(19 "Cmts.User" user "User.Comments")
		(21 "Eco1.User" user "User.Eco1")
		(23 "Eco2.User" user "User.Eco2")
		(25 "Edge.Cuts" user "Board Geometry/Outline")
		(27 "Margin" user)
		(31 "F.CrtYd" user "Package Geometry/Place Bound Top")
		(29 "B.CrtYd" user "Package Geometry/Place Bound Bottom")
		(35 "F.Fab" user "Ref Des/Assembly Top")
		(33 "B.Fab" user "Ref Des/Assembly Bottom")
	)
	(footprint ""
		(layer "B.Cu")
		(at 85.32241 -26.587704)
		(property "Reference" "R14"
			(at 0 0 0)
			(layer "B.SilkS")
			(hide yes)
			(effects
				(font
					(size 1.27 1.27)
				)
				(justify mirror)
			)
		)
		(property "Value" ""
			(at 0 0 0)
			(layer "B.Fab")
			(effects
				(font
					(size 1.27 1.27)
				)
				(justify mirror)
			)
		)
		(duplicate_pad_numbers_are_jumpers no)
		(fp_line
			(start -0.7874 -0.4064)
			(end -0.7874 0.4064)
			(stroke
				(width 0.1524)
				(type default)
			)
			(layer "B.SilkS")
		)
		(fp_line
			(start -0.7874 0.4064)
			(end 0.7874 0.4064)
			(stroke
				(width 0.1524)
				(type default)
			)
			(layer "B.SilkS")
		)
		(fp_line
			(start 0.7874 -0.4064)
			(end -0.7874 -0.4064)
			(stroke
				(width 0.1524)
				(type default)
			)
			(layer "B.SilkS")
		)
		(fp_line
			(start 0.7874 0.4064)
			(end 0.7874 -0.4064)
			(stroke
				(width 0.1524)
				(type default)
			)
			(layer "B.SilkS")
		)
		(fp_line
			(start -0.67945 -0.3048)
			(end -0.67945 0.3048)
			(stroke
				(width 0.1)
				(type default)
			)
			(layer "B.Fab")
		)
		(fp_line
			(start -0.67945 0.3048)
			(end -0.120396 0.3048)
			(stroke
				(width 0.1)
				(type default)
			)
			(layer "B.Fab")
		)
		(fp_line
			(start -0.12065 -0.3048)
			(end -0.67945 -0.3048)
			(stroke
				(width 0.1)
				(type default)
			)
			(layer "B.Fab")
		)
		(fp_line
			(start -0.12065 -0.2794)
			(end -0.12065 -0.3048)
			(stroke
				(width 0.1)
				(type default)
			)
			(layer "B.Fab")
		)
		(fp_line
			(start -0.120396 0.2794)
			(end 0.12065 0.2794)
			(stroke
				(width 0.1)
				(type default)
			)
			(layer "B.Fab")
		)
		(fp_line
			(start -0.120396 0.3048)
			(end -0.120396 0.2794)
			(stroke
				(width 0.1)
				(type default)
			)
			(layer "B.Fab")
		)
		(fp_line
			(start 0.12065 -0.305054)
			(end 0.12065 -0.2794)
			(stroke
				(width 0.1)
				(type default)
			)
			(layer "B.Fab")
		)
		(fp_line
			(start 0.12065 -0.2794)
			(end -0.12065 -0.2794)
			(stroke
				(width 0.1)
				(type default)
			)
			(layer "B.Fab")
		)
		(fp_line
			(start 0.12065 0.2794)
			(end 0.12065 0.3048)
			(stroke
				(width 0.1)
				(type default)
			)
			(layer "B.Fab")
		)
		(fp_line
			(start 0.12065 0.3048)
			(end 0.67945 0.3048)
			(stroke
				(width 0.1)
				(type default)
			)
			(layer "B.Fab")
		)
		(fp_line
			(start 0.67945 -0.305054)
			(end 0.12065 -0.305054)
			(stroke
				(width 0.1)
				(type default)
			)
			(layer "B.Fab")
		)
		(fp_line
			(start 0.67945 0.3048)
			(end 0.67945 -0.305054)
			(stroke
				(width 0.1)
				(type default)
			)
			(layer "B.Fab")
		)
		(pad "1" smd circle
			(at 0.40005 0 180)
			(size 0 0)
			(layers "B.Cu" "B.Mask" "B.Paste")
			(net "P3V3_AUX")
		)
		(pad "2" smd circle
			(at -0.40005 0 180)
			(size 0 0)
			(layers "B.Cu" "B.Mask" "B.Paste")
			(net "FRU_E2")
		)
	)
	(footprint ""
		(layer "B.Cu")
		(at 25.136856 -96.0882)
		(property "Reference" "C216"
			(at 0 0 0)
			(layer "B.SilkS")
			(hide yes)
			(effects
				(font
					(size 1.27 1.27)
				)
				(justify mirror)
			)
		)
		(property "Value" ""
			(at 0 0 0)
			(layer "B.Fab")
			(effects
				(font
					(size 1.27 1.27)
				)
				(justify mirror)
			)
		)
		(duplicate_pad_numbers_are_jumpers no)
		(fp_line
			(start -0.69215 -0.2921)
			(end -0.69215 0.2921)
			(stroke
				(width 0.1524)
				(type default)
			)
			(layer "B.SilkS")
		)
		(fp_line
			(start -0.69215 0.2921)
			(end 0.69215 0.2921)
			(stroke
				(width 0.1524)
				(type default)
			)
			(layer "B.SilkS")
		)
		(fp_line
			(start 0.69215 -0.2921)
			(end -0.69215 -0.2921)
			(stroke
				(width 0.1524)
				(type default)
			)
			(layer "B.SilkS")
		)
		(fp_line
			(start 0.69215 0.2921)
			(end 0.69215 -0.2921)
			(stroke
				(width 0.1524)
				(type default)
			)
			(layer "B.SilkS")
		)
		(fp_line
			(start -0.51435 -0.2794)
			(end -0.51435 0.2794)
			(stroke
				(width 0.1)
				(type default)
			)
			(layer "B.Fab")
		)
		(fp_line
			(start -0.51435 0.2794)
			(end 0.51435 0.2794)
			(stroke
				(width 0.1)
				(type default)
			)
			(layer "B.Fab")
		)
		(fp_line
			(start 0.51435 -0.2794)
			(end -0.51435 -0.2794)
			(stroke
				(width 0.1)
				(type default)
			)
			(layer "B.Fab")
		)
		(fp_line
			(start 0.51435 0.2794)
			(end 0.51435 -0.2794)
			(stroke
				(width 0.1)
				(type default)
			)
			(layer "B.Fab")
		)
		(pad "1" smd circle
			(at 0.40005 0 180)
			(size 0 0)
			(layers "B.Cu" "B.Mask" "B.Paste")
			(net "VCCIO3")
		)
		(pad "2" smd circle
			(at -0.40005 0 180)
			(size 0 0)
			(layers "B.Cu" "B.Mask" "B.Paste")
			(net "GND")
		)
		(zone
			(layer "B.Cu")
			(hatch none 0.5)
			(connect_pads
				(clearance 0)
			)
			(min_thickness 0.25)
			(keepout
				(tracks not_allowed)
				(vias allowed)
				(pads allowed)
				(copperpour not_allowed)
				(footprints allowed)
			)
			(placement
				(enabled no)
				(sheetname "")
			)
			(fill
				(thermal_gap 0.5)
				(thermal_bridge_width 0.5)
				(island_removal_mode 0)
			)
			(polygon
				(pts
					(xy 25.327356 -96.00057) (xy 25.235916 -95.942404) (xy 25.036526 -95.942404) (xy 24.946356 -96.00057)
					(xy 24.946356 -96.17583) (xy 25.036526 -96.23425) (xy 25.235916 -96.23425) (xy 25.327356 -96.176084)
				)
			)
		)
	)
	(footprint ""
		(layer "B.Cu")
		(at 83.018884 -38.13556 180)
		(property "Reference" "C15"
			(at 0 0 0)
			(layer "B.SilkS")
			(hide yes)
			(effects
				(font
					(size 1.27 1.27)
				)
				(justify mirror)
			)
		)
		(property "Value" ""
			(at 0 0 0)
			(layer "B.Fab")
			(effects
				(font
					(size 1.27 1.27)
				)
				(justify mirror)
			)
		)
		(duplicate_pad_numbers_are_jumpers no)
		(fp_line
			(start 0.7874 0.4064)
			(end 0.7874 -0.4064)
			(stroke
				(width 0.1524)
				(type default)
			)
			(layer "B.SilkS")
		)
		(fp_line
			(start 0.7874 -0.4064)
			(end -0.7874 -0.4064)
			(stroke
				(width 0.1524)
				(type default)
			)
			(layer "B.SilkS")
		)
		(fp_line
			(start -0.7874 0.4064)
			(end 0.7874 0.4064)
			(stroke
				(width 0.1524)
				(type default)
			)
			(layer "B.SilkS")
		)
		(fp_line
			(start -0.7874 -0.4064)
			(end -0.7874 0.4064)
			(stroke
				(width 0.1524)
				(type default)
			)
			(layer "B.SilkS")
		)
		(fp_line
			(start 0.67945 0.3048)
			(end 0.67945 -0.305054)
			(stroke
				(width 0.1)
				(type default)
			)
			(layer "B.Fab")
		)
		(fp_line
			(start 0.67945 -0.305054)
			(end 0.12065 -0.305054)
			(stroke
				(width 0.1)
				(type default)
			)
			(layer "B.Fab")
		)
		(fp_line
			(start 0.12065 0.3048)
			(end 0.67945 0.3048)
			(stroke
				(width 0.1)
				(type default)
			)
			(layer "B.Fab")
		)
		(fp_line
			(start 0.12065 0.2794)
			(end 0.12065 0.3048)
			(stroke
				(width 0.1)
				(type default)
			)
			(layer "B.Fab")
		)
		(fp_line
			(start 0.12065 -0.2794)
			(end -0.12065 -0.2794)
			(stroke
				(width 0.1)
				(type default)
			)
			(layer "B.Fab")
		)
		(fp_line
			(start 0.12065 -0.305054)
			(end 0.12065 -0.2794)
			(stroke
				(width 0.1)
				(type default)
			)
			(layer "B.Fab")
		)
		(fp_line
			(start -0.120396 0.3048)
			(end -0.120396 0.2794)
			(stroke
				(width 0.1)
				(type default)
			)
			(layer "B.Fab")
		)
		(fp_line
			(start -0.120396 0.2794)
			(end 0.12065 0.2794)
			(stroke
				(width 0.1)
				(type default)
			)
			(layer "B.Fab")
		)
		(fp_line
			(start -0.12065 -0.2794)
			(end -0.12065 -0.3048)
			(stroke
				(width 0.1)
				(type default)
			)
			(layer "B.Fab")
		)
		(fp_line
			(start -0.12065 -0.3048)
			(end -0.67945 -0.3048)
			(stroke
				(width 0.1)
				(type default)
			)
			(layer "B.Fab")
		)
		(fp_line
			(start -0.67945 0.3048)
			(end -0.120396 0.3048)
			(stroke
				(width 0.1)
				(type default)
			)
			(layer "B.Fab")
		)
		(fp_line
			(start -0.67945 -0.3048)
			(end -0.67945 0.3048)
			(stroke
				(width 0.1)
				(type default)
			)
			(layer "B.Fab")
		)
		(pad "1" smd circle
			(at 0.40005 0)
			(size 0 0)
			(layers "B.Cu" "B.Mask" "B.Paste")
			(net "P1V2_AUX")
		)
		(pad "2" smd circle
			(at -0.40005 0)
			(size 0 0)
			(layers "B.Cu" "B.Mask" "B.Paste")
			(net "GND")
		)
	)
	(footprint ""
		(layer "B.Cu")
		(at 58.44413 -47.990252)
		(property "Reference" "C104"
			(at 0 0 0)
			(layer "B.SilkS")
			(hide yes)
			(effects
				(font
					(size 1.27 1.27)
				)
				(justify mirror)
			)
		)
		(property "Value" ""
			(at 0 0 0)
			(layer "B.Fab")
			(effects
				(font
					(size 1.27 1.27)
				)
				(justify mirror)
			)
		)
		(duplicate_pad_numbers_are_jumpers no)
		(fp_line
			(start -0.7874 -0.4064)
			(end -0.7874 0.4064)
			(stroke
				(width 0.1524)
				(type default)
			)
			(layer "B.SilkS")
		)
		(fp_line
			(start -0.7874 0.4064)
			(end 0.7874 0.4064)
			(stroke
				(width 0.1524)
				(type default)
			)
			(layer "B.SilkS")
		)
		(fp_line
			(start 0.7874 -0.4064)
			(end -0.7874 -0.4064)
			(stroke
				(width 0.1524)
				(type default)
			)
			(layer "B.SilkS")
		)
		(fp_line
			(start 0.7874 0.4064)
			(end 0.7874 -0.4064)
			(stroke
				(width 0.1524)
				(type default)
			)
			(layer "B.SilkS")
		)
		(fp_line
			(start -0.67945 -0.3048)
			(end -0.67945 0.3048)
			(stroke
				(width 0.1)
				(type default)
			)
			(layer "B.Fab")
		)
		(fp_line
			(start -0.67945 0.3048)
			(end -0.120396 0.3048)
			(stroke
				(width 0.1)
				(type default)
			)
			(layer "B.Fab")
		)
		(fp_line
			(start -0.12065 -0.3048)
			(end -0.67945 -0.3048)
			(stroke
				(width 0.1)
				(type default)
			)
			(layer "B.Fab")
		)
		(fp_line
			(start -0.12065 -0.2794)
			(end -0.12065 -0.3048)
			(stroke
				(width 0.1)
				(type default)
			)
			(layer "B.Fab")
		)
		(fp_line
			(start -0.120396 0.2794)
			(end 0.12065 0.2794)
			(stroke
				(width 0.1)
				(type default)
			)
			(layer "B.Fab")
		)
		(fp_line
			(start -0.120396 0.3048)
			(end -0.120396 0.2794)
			(stroke
				(width 0.1)
				(type default)
			)
			(layer "B.Fab")
		)
		(fp_line
			(start 0.12065 -0.305054)
			(end 0.12065 -0.2794)
			(stroke
				(width 0.1)
				(type default)
			)
			(layer "B.Fab")
		)
		(fp_line
			(start 0.12065 -0.2794)
			(end -0.12065 -0.2794)
			(stroke
				(width 0.1)
				(type default)
			)
			(layer "B.Fab")
		)
		(fp_line
			(start 0.12065 0.2794)
			(end 0.12065 0.3048)
			(stroke
				(width 0.1)
				(type default)
			)
			(layer "B.Fab")
		)
		(fp_line
			(start 0.12065 0.3048)
			(end 0.67945 0.3048)
			(stroke
				(width 0.1)
				(type default)
			)
			(layer "B.Fab")
		)
		(fp_line
			(start 0.67945 -0.305054)
			(end 0.12065 -0.305054)
			(stroke
				(width 0.1)
				(type default)
			)
			(layer "B.Fab")
		)
		(fp_line
			(start 0.67945 0.3048)
			(end 0.67945 -0.305054)
			(stroke
				(width 0.1)
				(type default)
			)
			(layer "B.Fab")
		)
		(pad "1" smd circle
			(at 0.40005 0 180)
			(size 0 0)
			(layers "B.Cu" "B.Mask" "B.Paste")
			(net "P1V0_AUX")
		)
		(pad "2" smd circle
			(at -0.40005 0 180)
			(size 0 0)
			(layers "B.Cu" "B.Mask" "B.Paste")
			(net "GND")
		)
	)
	(footprint ""
		(layer "B.Cu")
		(at 85.29955 -39.347394 180)
		(property "Reference" "R368"
			(at 0 0 0)
			(layer "B.SilkS")
			(hide yes)
			(effects
				(font
					(size 1.27 1.27)
				)
				(justify mirror)
			)
		)
		(property "Value" ""
			(at 0 0 0)
			(layer "B.Fab")
			(effects
				(font
					(size 1.27 1.27)
				)
				(justify mirror)
			)
		)
		(duplicate_pad_numbers_are_jumpers no)
		(fp_line
			(start 0.7874 0.4064)
			(end 0.7874 -0.4064)
			(stroke
				(width 0.1524)
				(type default)
			)
			(layer "B.SilkS")
		)
		(fp_line
			(start 0.7874 -0.4064)
			(end -0.7874 -0.4064)
			(stroke
				(width 0.1524)
				(type default)
			)
			(layer "B.SilkS")
		)
		(fp_line
			(start -0.7874 0.4064)
			(end 0.7874 0.4064)
			(stroke
				(width 0.1524)
				(type default)
			)
			(layer "B.SilkS")
		)
		(fp_line
			(start -0.7874 -0.4064)
			(end -0.7874 0.4064)
			(stroke
				(width 0.1524)
				(type default)
			)
			(layer "B.SilkS")
		)
		(fp_line
			(start 0.67945 0.3048)
			(end 0.67945 -0.305054)
			(stroke
				(width 0.1)
				(type default)
			)
			(layer "B.Fab")
		)
		(fp_line
			(start 0.67945 -0.305054)
			(end 0.12065 -0.305054)
			(stroke
				(width 0.1)
				(type default)
			)
			(layer "B.Fab")
		)
		(fp_line
			(start 0.12065 0.3048)
			(end 0.67945 0.3048)
			(stroke
				(width 0.1)
				(type default)
			)
			(layer "B.Fab")
		)
		(fp_line
			(start 0.12065 0.2794)
			(end 0.12065 0.3048)
			(stroke
				(width 0.1)
				(type default)
			)
			(layer "B.Fab")
		)
		(fp_line
			(start 0.12065 -0.2794)
			(end -0.12065 -0.2794)
			(stroke
				(width 0.1)
				(type default)
			)
			(layer "B.Fab")
		)
		(fp_line
			(start 0.12065 -0.305054)
			(end 0.12065 -0.2794)
			(stroke
				(width 0.1)
				(type default)
			)
			(layer "B.Fab")
		)
		(fp_line
			(start -0.120396 0.3048)
			(end -0.120396 0.2794)
			(stroke
				(width 0.1)
				(type default)
			)
			(layer "B.Fab")
		)
		(fp_line
			(start -0.120396 0.2794)
			(end 0.12065 0.2794)
			(stroke
				(width 0.1)
				(type default)
			)
			(layer "B.Fab")
		)
		(fp_line
			(start -0.12065 -0.2794)
			(end -0.12065 -0.3048)
			(stroke
				(width 0.1)
				(type default)
			)
			(layer "B.Fab")
		)
		(fp_line
			(start -0.12065 -0.3048)
			(end -0.67945 -0.3048)
			(stroke
				(width 0.1)
				(type default)
			)
			(layer "B.Fab")
		)
		(fp_line
			(start -0.67945 0.3048)
			(end -0.120396 0.3048)
			(stroke
				(width 0.1)
				(type default)
			)
			(layer "B.Fab")
		)
		(fp_line
			(start -0.67945 -0.3048)
			(end -0.67945 0.3048)
			(stroke
				(width 0.1)
				(type default)
			)
			(layer "B.Fab")
		)
		(pad "1" smd circle
			(at 0.40005 0)
			(size 0 0)
			(layers "B.Cu" "B.Mask" "B.Paste")
			(net "M_BMC_DDR4_MCS_N")
		)
		(pad "2" smd circle
			(at -0.40005 0)
			(size 0 0)
			(layers "B.Cu" "B.Mask" "B.Paste")
			(net "P1V2_AUX")
		)
	)
	(footprint ""
		(layer "B.Cu")
		(at 75.438 -68.707)
		(property "Reference" ""
			(at 0 0 0)
			(layer "B.SilkS")
			(hide yes)
			(effects
				(font
					(size 1.27 1.27)
				)
				(justify mirror)
			)
		)
		(property "Value" ""
			(at 0 0 0)
			(layer "B.Fab")
			(effects
				(font
					(size 1.27 1.27)
				)
				(justify mirror)
			)
		)
		(duplicate_pad_numbers_are_jumpers no)
		(pad "1" smd circle
			(at 0 0 180)
			(size 0.9906 0.9906)
			(layers "B.Cu" "B.Mask" "B.Paste")
			(net "Net_599")
		)
		(zone
			(layer "B.Cu")
			(hatch none 0.5)
			(connect_pads
				(clearance 0)
			)
			(min_thickness 0.25)
			(keepout
				(tracks not_allowed)
				(vias allowed)
				(pads allowed)
				(copperpour not_allowed)
				(footprints allowed)
			)
			(placement
				(enabled no)
				(sheetname "")
			)
			(fill
				(thermal_gap 0.5)
				(thermal_bridge_width 0.5)
				(island_removal_mode 0)
			)
			(polygon
				(pts
					(arc
						(start 77.0636 -68.707)
						(mid 73.8124 -68.707)
						(end 77.0636 -68.707)
					)
				)
			)
		)
	)
	(footprint ""
		(layer "B.Cu")
		(at 79.4512 -66.1162 180)
		(property "Reference" "C301"
			(at 0 0 0)
			(layer "B.SilkS")
			(hide yes)
			(effects
				(font
					(size 1.27 1.27)
				)
				(justify mirror)
			)
		)
		(property "Value" ""
			(at 0 0 0)
			(layer "B.Fab")
			(effects
				(font
					(size 1.27 1.27)
				)
				(justify mirror)
			)
		)
		(duplicate_pad_numbers_are_jumpers no)
		(fp_line
			(start 0.7874 0.4064)
			(end 0.7874 -0.4064)
			(stroke
				(width 0.1524)
				(type default)
			)
			(layer "B.SilkS")
		)
		(fp_line
			(start 0.7874 -0.4064)
			(end -0.7874 -0.4064)
			(stroke
				(width 0.1524)
				(type default)
			)
			(layer "B.SilkS")
		)
		(fp_line
			(start -0.7874 0.4064)
			(end 0.7874 0.4064)
			(stroke
				(width 0.1524)
				(type default)
			)
			(layer "B.SilkS")
		)
		(fp_line
			(start -0.7874 -0.4064)
			(end -0.7874 0.4064)
			(stroke
				(width 0.1524)
				(type default)
			)
			(layer "B.SilkS")
		)
		(fp_line
			(start 0.67945 0.3048)
			(end 0.67945 -0.305054)
			(stroke
				(width 0.1)
				(type default)
			)
			(layer "B.Fab")
		)
		(fp_line
			(start 0.67945 -0.305054)
			(end 0.12065 -0.305054)
			(stroke
				(width 0.1)
				(type default)
			)
			(layer "B.Fab")
		)
		(fp_line
			(start 0.12065 0.3048)
			(end 0.67945 0.3048)
			(stroke
				(width 0.1)
				(type default)
			)
			(layer "B.Fab")
		)
		(fp_line
			(start 0.12065 0.2794)
			(end 0.12065 0.3048)
			(stroke
				(width 0.1)
				(type default)
			)
			(layer "B.Fab")
		)
		(fp_line
			(start 0.12065 -0.2794)
			(end -0.12065 -0.2794)
			(stroke
				(width 0.1)
				(type default)
			)
			(layer "B.Fab")
		)
		(fp_line
			(start 0.12065 -0.305054)
			(end 0.12065 -0.2794)
			(stroke
				(width 0.1)
				(type default)
			)
			(layer "B.Fab")
		)
		(fp_line
			(start -0.120396 0.3048)
			(end -0.120396 0.2794)
			(stroke
				(width 0.1)
				(type default)
			)
			(layer "B.Fab")
		)
		(fp_line
			(start -0.120396 0.2794)
			(end 0.12065 0.2794)
			(stroke
				(width 0.1)
				(type default)
			)
			(layer "B.Fab")
		)
		(fp_line
			(start -0.12065 -0.2794)
			(end -0.12065 -0.3048)
			(stroke
				(width 0.1)
				(type default)
			)
			(layer "B.Fab")
		)
		(fp_line
			(start -0.12065 -0.3048)
			(end -0.67945 -0.3048)
			(stroke
				(width 0.1)
				(type default)
			)
			(layer "B.Fab")
		)
		(fp_line
			(start -0.67945 0.3048)
			(end -0.120396 0.3048)
			(stroke
				(width 0.1)
				(type default)
			)
			(layer "B.Fab")
		)
		(fp_line
			(start -0.67945 -0.3048)
			(end -0.67945 0.3048)
			(stroke
				(width 0.1)
				(type default)
			)
			(layer "B.Fab")
		)
		(pad "1" smd circle
			(at 0.40005 0)
			(size 0 0)
			(layers "B.Cu" "B.Mask" "B.Paste")
			(net "P3V3_LDO")
		)
		(pad "2" smd circle
			(at -0.40005 0)
			(size 0 0)
			(layers "B.Cu" "B.Mask" "B.Paste")
			(net "GND")
		)
	)
)
